# T6G (Grand Teton) — schematic netlist excerpt (pin names and nets, part order shuffled) for the footprints in the layout excerpt that follows; sources: Cadence DE-HDL packaged netlist, KiCad conversion of 04192023_DAF0TMB3IC0_F0TG_MB_C_brd_V02_OCP.brd

C565  Q_CAP  22UF 4V 20% X6S  pkg C0402  page 279 : A = P0V9_CPU0_RT0_2A ; B = GND
R1679  Q_RES  10 1% CHIP  pkg 0402LF  page 91 : A = I3C_SPD_DDRAF_CPU0_SDA ; B = I3C_SPD_DDRF_CPU0_SDA

(kicad_pcb
	(version 20260206)
	(generator "pcbnew")
	(generator_version "10.0")
	(general
		(thickness 1.6)
		(legacy_teardrops no)
	)
	(paper "A4")
	(title_block
		(title "04192023_DAF0TMB3IC0_F0TG_MB_C_brd_V02_OCP.brd")
		(comment 1 "Grand Teton / footprints 6552-6553 of 8354")
	)
	(layers
		(0 "F.Cu" signal "TOP")
		(4 "In1.Cu" signal "GND")
		(6 "In2.Cu" signal "IN1")
		(8 "In3.Cu" signal "GND1")
		(10 "In4.Cu" signal "IN2")
		(12 "In5.Cu" signal "GND2")
		(14 "In6.Cu" signal "IN3")
		(16 "In7.Cu" signal "GND3")
		(18 "In8.Cu" signal "VCC")
		(20 "In9.Cu" signal "VCC1")
		(22 "In10.Cu" signal "GND4")
		(24 "In11.Cu" signal "IN4")
		(26 "In12.Cu" signal "GND5")
		(28 "In13.Cu" signal "IN5")
		(30 "In14.Cu" signal "GND6")
		(32 "In15.Cu" signal "IN6")
		(34 "In16.Cu" signal "GND7")
		(2 "B.Cu" signal "BOTTOM")
		(9 "F.Adhes" user "F.Adhesive")
		(11 "B.Adhes" user "B.Adhesive")
		(13 "F.Paste" user "Package Geometry/Pastemask Top")
		(15 "B.Paste" user "Package Geometry/Pastemask Bottom")
		(5 "F.SilkS" user "Ref Des/Silkscreen Top")
		(7 "B.SilkS" user "Ref Des/Silkscreen Bottom")
		(1 "F.Mask" user "Board Geometry/Soldermask Top")
		(3 "B.Mask" user "Board Geometry/Soldermask Bottom")
		(17 "Dwgs.User" user "User.Drawings")
		(19 "Cmts.User" user "User.Comments")
		(21 "Eco1.User" user "User.Eco1")
		(23 "Eco2.User" user "User.Eco2")
		(25 "Edge.Cuts" user "Board Geometry/Outline")
		(27 "Margin" user)
		(31 "F.CrtYd" user "Package Geometry/Place Bound Top")
		(29 "B.CrtYd" user "Package Geometry/Place Bound Bottom")
		(35 "F.Fab" user "Ref Des/Assembly Top")
		(33 "B.Fab" user "Ref Des/Assembly Bottom")
	)
	(footprint ""
		(layer "B.Cu")
		(at 304.590958 -398.942052 90)
		(property "Reference" "C565"
			(at 0 0 90)
			(layer "B.SilkS")
			(hide yes)
			(effects
				(font
					(size 1.27 1.27)
				)
				(justify mirror)
			)
		)
		(property "Value" ""
			(at 0 0 90)
			(layer "B.Fab")
			(effects
				(font
					(size 1.27 1.27)
				)
				(justify mirror)
			)
		)
		(duplicate_pad_numbers_are_jumpers no)
		(fp_line
			(start 0.7874 -0.4064)
			(end -0.7874 -0.4064)
			(stroke
				(width 0.1524)
				(type default)
			)
			(layer "B.SilkS")
		)
		(fp_line
			(start -0.7874 -0.4064)
			(end -0.7874 0.4064)
			(stroke
				(width 0.1524)
				(type default)
			)
			(layer "B.SilkS")
		)
		(fp_line
			(start 0.7874 0.4064)
			(end 0.7874 -0.4064)
			(stroke
				(width 0.1524)
				(type default)
			)
			(layer "B.SilkS")
		)
		(fp_line
			(start -0.7874 0.4064)
			(end 0.7874 0.4064)
			(stroke
				(width 0.1524)
				(type default)
			)
			(layer "B.SilkS")
		)
		(fp_line
			(start 0.67945 -0.305054)
			(end 0.12065 -0.305054)
			(stroke
				(width 0.1)
				(type default)
			)
			(layer "B.Fab")
		)
		(fp_line
			(start 0.12065 -0.305054)
			(end 0.12065 -0.2794)
			(stroke
				(width 0.1)
				(type default)
			)
			(layer "B.Fab")
		)
		(fp_line
			(start -0.12065 -0.3048)
			(end -0.67945 -0.3048)
			(stroke
				(width 0.1)
				(type default)
			)
			(layer "B.Fab")
		)
		(fp_line
			(start -0.67945 -0.3048)
			(end -0.67945 0.3048)
			(stroke
				(width 0.1)
				(type default)
			)
			(layer "B.Fab")
		)
		(fp_line
			(start 0.12065 -0.2794)
			(end -0.12065 -0.2794)
			(stroke
				(width 0.1)
				(type default)
			)
			(layer "B.Fab")
		)
		(fp_line
			(start -0.12065 -0.2794)
			(end -0.12065 -0.3048)
			(stroke
				(width 0.1)
				(type default)
			)
			(layer "B.Fab")
		)
		(fp_line
			(start 0.12065 0.2794)
			(end 0.12065 0.3048)
			(stroke
				(width 0.1)
				(type default)
			)
			(layer "B.Fab")
		)
		(fp_line
			(start -0.120396 0.2794)
			(end 0.12065 0.2794)
			(stroke
				(width 0.1)
				(type default)
			)
			(layer "B.Fab")
		)
		(fp_line
			(start 0.67945 0.3048)
			(end 0.67945 -0.305054)
			(stroke
				(width 0.1)
				(type default)
			)
			(layer "B.Fab")
		)
		(fp_line
			(start 0.12065 0.3048)
			(end 0.67945 0.3048)
			(stroke
				(width 0.1)
				(type default)
			)
			(layer "B.Fab")
		)
		(fp_line
			(start -0.120396 0.3048)
			(end -0.120396 0.2794)
			(stroke
				(width 0.1)
				(type default)
			)
			(layer "B.Fab")
		)
		(fp_line
			(start -0.67945 0.3048)
			(end -0.120396 0.3048)
			(stroke
				(width 0.1)
				(type default)
			)
			(layer "B.Fab")
		)
		(pad "1" smd circle
			(at 0.40005 0 270)
			(size 0 0)
			(layers "B.Cu" "B.Mask" "B.Paste")
			(net "P0V9_CPU0_RT0_2A")
		)
		(pad "2" smd circle
			(at -0.40005 0 270)
			(size 0 0)
			(layers "B.Cu" "B.Mask" "B.Paste")
			(net "GND")
		)
	)
	(footprint ""
		(layer "B.Cu")
		(at 268.892528 -195.859146 180)
		(property "Reference" "R1679"
			(at 0 0 0)
			(layer "B.SilkS")
			(hide yes)
			(effects
				(font
					(size 1.27 1.27)
				)
				(justify mirror)
			)
		)
		(property "Value" ""
			(at 0 0 0)
			(layer "B.Fab")
			(effects
				(font
					(size 1.27 1.27)
				)
				(justify mirror)
			)
		)
		(duplicate_pad_numbers_are_jumpers no)
		(fp_line
			(start 0.7874 0.4064)
			(end 0.7874 -0.4064)
			(stroke
				(width 0.1524)
				(type default)
			)
			(layer "B.SilkS")
		)
		(fp_line
			(start 0.7874 -0.4064)
			(end -0.7874 -0.4064)
			(stroke
				(width 0.1524)
				(type default)
			)
			(layer "B.SilkS")
		)
		(fp_line
			(start -0.7874 0.4064)
			(end 0.7874 0.4064)
			(stroke
				(width 0.1524)
				(type default)
			)
			(layer "B.SilkS")
		)
		(fp_line
			(start -0.7874 -0.4064)
			(end -0.7874 0.4064)
			(stroke
				(width 0.1524)
				(type default)
			)
			(layer "B.SilkS")
		)
		(fp_line
			(start 0.67945 0.3048)
			(end 0.67945 -0.305054)
			(stroke
				(width 0.1)
				(type default)
			)
			(layer "B.Fab")
		)
		(fp_line
			(start 0.67945 -0.305054)
			(end 0.12065 -0.305054)
			(stroke
				(width 0.1)
				(type default)
			)
			(layer "B.Fab")
		)
		(fp_line
			(start 0.12065 0.3048)
			(end 0.67945 0.3048)
			(stroke
				(width 0.1)
				(type default)
			)
			(layer "B.Fab")
		)
		(fp_line
			(start 0.12065 0.2794)
			(end 0.12065 0.3048)
			(stroke
				(width 0.1)
				(type default)
			)
			(layer "B.Fab")
		)
		(fp_line
			(start 0.12065 -0.2794)
			(end -0.12065 -0.2794)
			(stroke
				(width 0.1)
				(type default)
			)
			(layer "B.Fab")
		)
		(fp_line
			(start 0.12065 -0.305054)
			(end 0.12065 -0.2794)
			(stroke
				(width 0.1)
				(type default)
			)
			(layer "B.Fab")
		)
		(fp_line
			(start -0.120396 0.3048)
			(end -0.120396 0.2794)
			(stroke
				(width 0.1)
				(type default)
			)
			(layer "B.Fab")
		)
		(fp_line
			(start -0.120396 0.2794)
			(end 0.12065 0.2794)
			(stroke
				(width 0.1)
				(type default)
			)
			(layer "B.Fab")
		)
		(fp_line
			(start -0.12065 -0.2794)
			(end -0.12065 -0.3048)
			(stroke
				(width 0.1)
				(type default)
			)
			(layer "B.Fab")
		)
		(fp_line
			(start -0.12065 -0.3048)
			(end -0.67945 -0.3048)
			(stroke
				(width 0.1)
				(type default)
			)
			(layer "B.Fab")
		)
		(fp_line
			(start -0.67945 0.3048)
			(end -0.120396 0.3048)
			(stroke
				(width 0.1)
				(type default)
			)
			(layer "B.Fab")
		)
		(fp_line
			(start -0.67945 -0.3048)
			(end -0.67945 0.3048)
			(stroke
				(width 0.1)
				(type default)
			)
			(layer "B.Fab")
		)
		(pad "1" smd circle
			(at 0.40005 0)
			(size 0 0)
			(layers "B.Cu" "B.Mask" "B.Paste")
			(net "I3C_SPD_DDRAF_CPU0_SDA")
		)
		(pad "2" smd circle
			(at -0.40005 0)
			(size 0 0)
			(layers "B.Cu" "B.Mask" "B.Paste")
			(net "I3C_SPD_DDRF_CPU0_SDA")
		)
	)
)
